# S9S_MB_2U (Grand Teton) — schematic netlist excerpt (pin names and nets, part order shuffled) for the footprints in the layout excerpt that follows; sources: Cadence DE-HDL packaged netlist, KiCad conversion of 03242023_DA0F0TMBIJ0_F0T_Motherboard_J_brd_V01_OCP.brd

R1680  Q_RES  0 5% CHIP  pkg 0402LF  page 208 : A = FM_PLD_CLK_25M_EN ; B = FM_CK440Q_DEV_25M_EN
R2577  Q_RES  0 5% CHIP  pkg 0402LF  page 296 : A = FM_PVCCD_HV_CPU1_EN ; B = PVCCD_HV_CPU1_EN_R

(kicad_pcb
	(version 20260206)
	(generator "pcbnew")
	(generator_version "10.0")
	(general
		(thickness 1.6)
		(legacy_teardrops no)
	)
	(paper "A4")
	(title_block
		(title "03242023_DA0F0TMBIJ0_F0T_Motherboard_J_brd_V01_OCP.brd")
		(comment 1 "Grand Teton / footprints 4181-4182 of 6105")
	)
	(layers
		(0 "F.Cu" signal "TOP")
		(4 "In1.Cu" signal "GND")
		(6 "In2.Cu" signal "IN1")
		(8 "In3.Cu" signal "GND1")
		(10 "In4.Cu" signal "IN2")
		(12 "In5.Cu" signal "GND2")
		(14 "In6.Cu" signal "IN3")
		(16 "In7.Cu" signal "GND3")
		(18 "In8.Cu" signal "VCC")
		(20 "In9.Cu" signal "VCC1")
		(22 "In10.Cu" signal "GND4")
		(24 "In11.Cu" signal "IN4")
		(26 "In12.Cu" signal "GND5")
		(28 "In13.Cu" signal "IN5")
		(30 "In14.Cu" signal "GND6")
		(32 "In15.Cu" signal "IN6")
		(34 "In16.Cu" signal "GND7")
		(2 "B.Cu" signal "BOTTOM")
		(9 "F.Adhes" user "F.Adhesive")
		(11 "B.Adhes" user "B.Adhesive")
		(13 "F.Paste" user "Package Geometry/Pastemask Top")
		(15 "B.Paste" user "Package Geometry/Pastemask Bottom")
		(5 "F.SilkS" user "Ref Des/Silkscreen Top")
		(7 "B.SilkS" user "Ref Des/Silkscreen Bottom")
		(1 "F.Mask" user "Board Geometry/Soldermask Top")
		(3 "B.Mask" user "Board Geometry/Soldermask Bottom")
		(17 "Dwgs.User" user "User.Drawings")
		(19 "Cmts.User" user "User.Comments")
		(21 "Eco1.User" user "User.Eco1")
		(23 "Eco2.User" user "User.Eco2")
		(25 "Edge.Cuts" user "Board Geometry/Outline")
		(27 "Margin" user)
		(31 "F.CrtYd" user "Package Geometry/Place Bound Top")
		(29 "B.CrtYd" user "Package Geometry/Place Bound Bottom")
		(35 "F.Fab" user "Ref Des/Assembly Top")
		(33 "B.Fab" user "Ref Des/Assembly Bottom")
	)
	(footprint ""
		(layer "B.Cu")
		(at 21.914612 -167.548814 180)
		(property "Reference" "R2577"
			(at 0 0 0)
			(layer "B.SilkS")
			(hide yes)
			(effects
				(font
					(size 1.27 1.27)
				)
				(justify mirror)
			)
		)
		(property "Value" ""
			(at 0 0 0)
			(layer "B.Fab")
			(effects
				(font
					(size 1.27 1.27)
				)
				(justify mirror)
			)
		)
		(duplicate_pad_numbers_are_jumpers no)
		(fp_line
			(start 0.7874 0.4064)
			(end 0.7874 -0.4064)
			(stroke
				(width 0.1524)
				(type default)
			)
			(layer "B.SilkS")
		)
		(fp_line
			(start 0.7874 -0.4064)
			(end -0.7874 -0.4064)
			(stroke
				(width 0.1524)
				(type default)
			)
			(layer "B.SilkS")
		)
		(fp_line
			(start -0.7874 0.4064)
			(end 0.7874 0.4064)
			(stroke
				(width 0.1524)
				(type default)
			)
			(layer "B.SilkS")
		)
		(fp_line
			(start -0.7874 -0.4064)
			(end -0.7874 0.4064)
			(stroke
				(width 0.1524)
				(type default)
			)
			(layer "B.SilkS")
		)
		(fp_line
			(start 0.67945 0.3048)
			(end 0.67945 -0.305054)
			(stroke
				(width 0.1)
				(type default)
			)
			(layer "B.Fab")
		)
		(fp_line
			(start 0.67945 -0.305054)
			(end 0.12065 -0.305054)
			(stroke
				(width 0.1)
				(type default)
			)
			(layer "B.Fab")
		)
		(fp_line
			(start 0.12065 0.3048)
			(end 0.67945 0.3048)
			(stroke
				(width 0.1)
				(type default)
			)
			(layer "B.Fab")
		)
		(fp_line
			(start 0.12065 0.2794)
			(end 0.12065 0.3048)
			(stroke
				(width 0.1)
				(type default)
			)
			(layer "B.Fab")
		)
		(fp_line
			(start 0.12065 -0.2794)
			(end -0.12065 -0.2794)
			(stroke
				(width 0.1)
				(type default)
			)
			(layer "B.Fab")
		)
		(fp_line
			(start 0.12065 -0.305054)
			(end 0.12065 -0.2794)
			(stroke
				(width 0.1)
				(type default)
			)
			(layer "B.Fab")
		)
		(fp_line
			(start -0.120396 0.3048)
			(end -0.120396 0.2794)
			(stroke
				(width 0.1)
				(type default)
			)
			(layer "B.Fab")
		)
		(fp_line
			(start -0.120396 0.2794)
			(end 0.12065 0.2794)
			(stroke
				(width 0.1)
				(type default)
			)
			(layer "B.Fab")
		)
		(fp_line
			(start -0.12065 -0.2794)
			(end -0.12065 -0.3048)
			(stroke
				(width 0.1)
				(type default)
			)
			(layer "B.Fab")
		)
		(fp_line
			(start -0.12065 -0.3048)
			(end -0.67945 -0.3048)
			(stroke
				(width 0.1)
				(type default)
			)
			(layer "B.Fab")
		)
		(fp_line
			(start -0.67945 0.3048)
			(end -0.120396 0.3048)
			(stroke
				(width 0.1)
				(type default)
			)
			(layer "B.Fab")
		)
		(fp_line
			(start -0.67945 -0.3048)
			(end -0.67945 0.3048)
			(stroke
				(width 0.1)
				(type default)
			)
			(layer "B.Fab")
		)
		(pad "1" smd circle
			(at 0.40005 0)
			(size 0 0)
			(layers "B.Cu" "B.Mask" "B.Paste")
			(net "FM_PVCCD_HV_CPU1_EN")
		)
		(pad "2" smd circle
			(at -0.40005 0)
			(size 0 0)
			(layers "B.Cu" "B.Mask" "B.Paste")
			(net "PVCCD_HV_CPU1_EN_R")
		)
	)
	(footprint ""
		(layer "B.Cu")
		(at 251.007626 -105.256584 90)
		(property "Reference" "R1680"
			(at 0 0 90)
			(layer "B.SilkS")
			(hide yes)
			(effects
				(font
					(size 1.27 1.27)
				)
				(justify mirror)
			)
		)
		(property "Value" ""
			(at 0 0 90)
			(layer "B.Fab")
			(effects
				(font
					(size 1.27 1.27)
				)
				(justify mirror)
			)
		)
		(duplicate_pad_numbers_are_jumpers no)
		(fp_line
			(start 0.7874 -0.4064)
			(end -0.7874 -0.4064)
			(stroke
				(width 0.1524)
				(type default)
			)
			(layer "B.SilkS")
		)
		(fp_line
			(start -0.7874 -0.4064)
			(end -0.7874 0.4064)
			(stroke
				(width 0.1524)
				(type default)
			)
			(layer "B.SilkS")
		)
		(fp_line
			(start 0.7874 0.4064)
			(end 0.7874 -0.4064)
			(stroke
				(width 0.1524)
				(type default)
			)
			(layer "B.SilkS")
		)
		(fp_line
			(start -0.7874 0.4064)
			(end 0.7874 0.4064)
			(stroke
				(width 0.1524)
				(type default)
			)
			(layer "B.SilkS")
		)
		(fp_line
			(start 0.67945 -0.305054)
			(end 0.12065 -0.305054)
			(stroke
				(width 0.1)
				(type default)
			)
			(layer "B.Fab")
		)
		(fp_line
			(start 0.12065 -0.305054)
			(end 0.12065 -0.2794)
			(stroke
				(width 0.1)
				(type default)
			)
			(layer "B.Fab")
		)
		(fp_line
			(start -0.12065 -0.3048)
			(end -0.67945 -0.3048)
			(stroke
				(width 0.1)
				(type default)
			)
			(layer "B.Fab")
		)
		(fp_line
			(start -0.67945 -0.3048)
			(end -0.67945 0.3048)
			(stroke
				(width 0.1)
				(type default)
			)
			(layer "B.Fab")
		)
		(fp_line
			(start 0.12065 -0.2794)
			(end -0.12065 -0.2794)
			(stroke
				(width 0.1)
				(type default)
			)
			(layer "B.Fab")
		)
		(fp_line
			(start -0.12065 -0.2794)
			(end -0.12065 -0.3048)
			(stroke
				(width 0.1)
				(type default)
			)
			(layer "B.Fab")
		)
		(fp_line
			(start 0.12065 0.2794)
			(end 0.12065 0.3048)
			(stroke
				(width 0.1)
				(type default)
			)
			(layer "B.Fab")
		)
		(fp_line
			(start -0.120396 0.2794)
			(end 0.12065 0.2794)
			(stroke
				(width 0.1)
				(type default)
			)
			(layer "B.Fab")
		)
		(fp_line
			(start 0.67945 0.3048)
			(end 0.67945 -0.305054)
			(stroke
				(width 0.1)
				(type default)
			)
			(layer "B.Fab")
		)
		(fp_line
			(start 0.12065 0.3048)
			(end 0.67945 0.3048)
			(stroke
				(width 0.1)
				(type default)
			)
			(layer "B.Fab")
		)
		(fp_line
			(start -0.120396 0.3048)
			(end -0.120396 0.2794)
			(stroke
				(width 0.1)
				(type default)
			)
			(layer "B.Fab")
		)
		(fp_line
			(start -0.67945 0.3048)
			(end -0.120396 0.3048)
			(stroke
				(width 0.1)
				(type default)
			)
			(layer "B.Fab")
		)
		(pad "1" smd circle
			(at 0.40005 0 270)
			(size 0 0)
			(layers "B.Cu" "B.Mask" "B.Paste")
			(net "FM_PLD_CLK_25M_EN")
		)
		(pad "2" smd circle
			(at -0.40005 0 270)
			(size 0 0)
			(layers "B.Cu" "B.Mask" "B.Paste")
			(net "FM_CK440Q_DEV_25M_EN")
		)
	)
)
